# T6G (Grand Teton) — schematic netlist excerpt (pin names and nets, part order shuffled) for the footprints in the layout excerpt that follows; sources: Cadence DE-HDL packaged netlist, KiCad conversion of 04192023_DAF0TMB3IC0_F0TG_MB_C_brd_V02_OCP.brd

PD15  ZENER_AC  5.0SMDJ14A IC  pkg D2723_SMCXC  page 268 : A = GND ; C = P12V_PSU_FUSE

(kicad_pcb
	(version 20260206)
	(generator "pcbnew")
	(generator_version "10.0")
	(general
		(thickness 1.6)
		(legacy_teardrops no)
	)
	(paper "A4")
	(title_block
		(title "04192023_DAF0TMB3IC0_F0TG_MB_C_brd_V02_OCP.brd")
		(comment 1 "Grand Teton / footprints 1345-1345 of 8354")
	)
	(layers
		(0 "F.Cu" signal "TOP")
		(4 "In1.Cu" signal "GND")
		(6 "In2.Cu" signal "IN1")
		(8 "In3.Cu" signal "GND1")
		(10 "In4.Cu" signal "IN2")
		(12 "In5.Cu" signal "GND2")
		(14 "In6.Cu" signal "IN3")
		(16 "In7.Cu" signal "GND3")
		(18 "In8.Cu" signal "VCC")
		(20 "In9.Cu" signal "VCC1")
		(22 "In10.Cu" signal "GND4")
		(24 "In11.Cu" signal "IN4")
		(26 "In12.Cu" signal "GND5")
		(28 "In13.Cu" signal "IN5")
		(30 "In14.Cu" signal "GND6")
		(32 "In15.Cu" signal "IN6")
		(34 "In16.Cu" signal "GND7")
		(2 "B.Cu" signal "BOTTOM")
		(9 "F.Adhes" user "F.Adhesive")
		(11 "B.Adhes" user "B.Adhesive")
		(13 "F.Paste" user "Package Geometry/Pastemask Top")
		(15 "B.Paste" user "Package Geometry/Pastemask Bottom")
		(5 "F.SilkS" user "Ref Des/Silkscreen Top")
		(7 "B.SilkS" user "Ref Des/Silkscreen Bottom")
		(1 "F.Mask" user "Board Geometry/Soldermask Top")
		(3 "B.Mask" user "Board Geometry/Soldermask Bottom")
		(17 "Dwgs.User" user "User.Drawings")
		(19 "Cmts.User" user "User.Comments")
		(21 "Eco1.User" user "User.Eco1")
		(23 "Eco2.User" user "User.Eco2")
		(25 "Edge.Cuts" user "Board Geometry/Outline")
		(27 "Margin" user)
		(31 "F.CrtYd" user "Package Geometry/Place Bound Top")
		(29 "B.CrtYd" user "Package Geometry/Place Bound Bottom")
		(35 "F.Fab" user "Ref Des/Assembly Top")
		(33 "B.Fab" user "Ref Des/Assembly Bottom")
	)
	(footprint ""
		(layer "F.Cu")
		(at 246.04726 -418.118544 -90)
		(property "Reference" "PD15"
			(at -1.40208 3.638804 90)
			(unlocked yes)
			(layer "F.SilkS")
			(effects
				(font
					(size 0.7874 0.5842)
					(thickness 0.1524)
				)
				(justify left)
			)
		)
		(property "Value" ""
			(at 0 0 270)
			(layer "F.Fab")
			(effects
				(font
					(size 1.27 1.27)
				)
			)
		)
		(duplicate_pad_numbers_are_jumpers no)
		(fp_line
			(start -4.664456 3.109976)
			(end -4.664456 -3.109976)
			(stroke
				(width 0.1524)
				(type default)
			)
			(layer "F.SilkS")
		)
		(fp_line
			(start 4.156202 3.109976)
			(end 4.183126 3.109976)
			(stroke
				(width 0.1524)
				(type default)
			)
			(layer "F.SilkS")
		)
		(fp_line
			(start 4.743704 3.109976)
			(end 4.6101 3.109976)
			(stroke
				(width 0.1524)
				(type default)
			)
			(layer "F.SilkS")
		)
		(fp_line
			(start 4.743704 3.109976)
			(end 5.4102 3.109976)
			(stroke
				(width 0.1524)
				(type default)
			)
			(layer "F.SilkS")
		)
		(fp_line
			(start 4.769104 3.109976)
			(end -4.664456 3.109976)
			(stroke
				(width 0.1524)
				(type default)
			)
			(layer "F.SilkS")
		)
		(fp_line
			(start 4.794504 3.109976)
			(end 3.554984 3.109976)
			(stroke
				(width 0.1524)
				(type default)
			)
			(layer "F.SilkS")
		)
		(fp_line
			(start 5.4102 3.109976)
			(end 5.4102 -3.109976)
			(stroke
				(width 0.1524)
				(type default)
			)
			(layer "F.SilkS")
		)
		(fp_line
			(start 4.715002 3.035554)
			(end 4.7117 2.984754)
			(stroke
				(width 0.1524)
				(type default)
			)
			(layer "F.SilkS")
		)
		(fp_line
			(start 0.762 1.27)
			(end 0.762 -1.27)
			(stroke
				(width 0.1524)
				(type default)
			)
			(layer "F.SilkS")
		)
		(fp_line
			(start -0.508 1.016)
			(end -0.508 -1.016)
			(stroke
				(width 0.1524)
				(type default)
			)
			(layer "F.SilkS")
		)
		(fp_line
			(start -1.0668 0)
			(end -0.6096 0)
			(stroke
				(width 0.1524)
				(type default)
			)
			(layer "F.SilkS")
		)
		(fp_line
			(start 0.762 0)
			(end -0.508 1.016)
			(stroke
				(width 0.1524)
				(type default)
			)
			(layer "F.SilkS")
		)
		(fp_line
			(start 0.762 0)
			(end 1.2192 0)
			(stroke
				(width 0.1524)
				(type default)
			)
			(layer "F.SilkS")
		)
		(fp_line
			(start -0.508 -1.016)
			(end 0.762 0)
			(stroke
				(width 0.1524)
				(type default)
			)
			(layer "F.SilkS")
		)
		(fp_line
			(start -4.664456 -3.109976)
			(end 4.743704 -3.109976)
			(stroke
				(width 0.1524)
				(type default)
			)
			(layer "F.SilkS")
		)
		(fp_line
			(start 4.183126 -3.109976)
			(end 4.794504 -3.109976)
			(stroke
				(width 0.1524)
				(type default)
			)
			(layer "F.SilkS")
		)
		(fp_line
			(start 4.511802 -3.109976)
			(end 4.207002 -3.109976)
			(stroke
				(width 0.1524)
				(type default)
			)
			(layer "F.SilkS")
		)
		(fp_line
			(start 4.6101 -3.109976)
			(end 4.283202 -3.109976)
			(stroke
				(width 0.1524)
				(type default)
			)
			(layer "F.SilkS")
		)
		(fp_line
			(start 4.695444 -3.109976)
			(end 4.695444 3.109976)
			(stroke
				(width 0.1524)
				(type default)
			)
			(layer "F.SilkS")
		)
		(fp_line
			(start 4.70535 -3.109976)
			(end 4.70535 3.109976)
			(stroke
				(width 0.1524)
				(type default)
			)
			(layer "F.SilkS")
		)
		(fp_line
			(start 4.70535 -3.109976)
			(end 4.70535 3.109976)
			(stroke
				(width 0.1524)
				(type default)
			)
			(layer "F.SilkS")
		)
		(fp_line
			(start 4.70535 -3.109976)
			(end 4.70535 3.109976)
			(stroke
				(width 0.1524)
				(type default)
			)
			(layer "F.SilkS")
		)
		(fp_line
			(start 4.805426 -3.109976)
			(end 4.805426 3.109976)
			(stroke
				(width 0.1524)
				(type default)
			)
			(layer "F.SilkS")
		)
		(fp_line
			(start 4.932426 -3.109976)
			(end 4.932426 3.109976)
			(stroke
				(width 0.1524)
				(type default)
			)
			(layer "F.SilkS")
		)
		(fp_line
			(start 5.008626 -3.109976)
			(end 5.008626 3.109976)
			(stroke
				(width 0.1524)
				(type default)
			)
			(layer "F.SilkS")
		)
		(fp_line
			(start 5.110226 -3.109976)
			(end 5.110226 3.109976)
			(stroke
				(width 0.1524)
				(type default)
			)
			(layer "F.SilkS")
		)
		(fp_line
			(start 5.211826 -3.109976)
			(end 5.211826 3.109976)
			(stroke
				(width 0.1524)
				(type default)
			)
			(layer "F.SilkS")
		)
		(fp_line
			(start 5.262626 -3.109976)
			(end 5.262626 3.109976)
			(stroke
				(width 0.1524)
				(type default)
			)
			(layer "F.SilkS")
		)
		(fp_line
			(start 5.313426 -3.109976)
			(end 5.313426 3.109976)
			(stroke
				(width 0.1524)
				(type default)
			)
			(layer "F.SilkS")
		)
		(fp_line
			(start 5.4102 -3.109976)
			(end 4.783074 -3.109976)
			(stroke
				(width 0.1524)
				(type default)
			)
			(layer "F.SilkS")
		)
		(fp_line
			(start -4.065016 3.109976)
			(end -4.065016 -3.109976)
			(stroke
				(width 0.1)
				(type default)
			)
			(layer "F.Fab")
		)
		(fp_line
			(start 4.065016 3.109976)
			(end -4.065016 3.109976)
			(stroke
				(width 0.1)
				(type default)
			)
			(layer "F.Fab")
		)
		(fp_line
			(start -4.065016 -3.109976)
			(end 4.065016 -3.109976)
			(stroke
				(width 0.1)
				(type default)
			)
			(layer "F.Fab")
		)
		(fp_line
			(start 4.065016 -3.109976)
			(end 4.065016 3.109976)
			(stroke
				(width 0.1)
				(type default)
			)
			(layer "F.Fab")
		)
		(fp_text user "-"
			(at 6.643624 0.40005 90)
			(unlocked yes)
			(layer "F.SilkS")
			(effects
				(font
					(size 1.905 1.4224)
					(thickness 0.1524)
				)
				(justify left)
			)
		)
		(fp_text user "+"
			(at -4.5974 0.24765 90)
			(unlocked yes)
			(layer "F.SilkS")
			(effects
				(font
					(size 1.905 1.4224)
					(thickness 0.1524)
				)
				(justify left)
			)
		)
		(fp_text user "-"
			(at 6.643624 0.40005 90)
			(unlocked yes)
			(layer "F.Fab")
			(effects
				(font
					(size 1.905 1.4224)
					(thickness 0.1524)
				)
				(justify left)
			)
		)
		(fp_text user "+"
			(at -4.5974 0.24765 90)
			(unlocked yes)
			(layer "F.Fab")
			(effects
				(font
					(size 1.905 1.4224)
					(thickness 0.1524)
				)
				(justify left)
			)
		)
		(pad "A" smd rect
			(at -3.299968 0 90)
			(size 2.413 3.302)
			(layers "F.Cu" "F.Mask" "F.Paste")
			(net "GND")
		)
		(pad "C" smd rect
			(at 3.299968 0 90)
			(size 2.413 3.302)
			(layers "F.Cu" "F.Mask" "F.Paste")
			(net "P12V_PSU_FUSE")
		)
	)
)
